G04*
G04 #@! TF.GenerationSoftware,Altium Limited,Altium Designer,23.6.0 (18)*
G04*
G04 Layer_Color=0*
%FSLAX44Y44*%
%MOMM*%
G71*
G04*
G04 #@! TF.SameCoordinates,B62FFF2A-40BB-47C2-B022-6C0D6E2DF31E*
G04*
G04*
G04 #@! TF.FilePolarity,Positive*
G04*
G01*
G75*
%ADD72C,0.0254*%
D72*
X10750Y0D02*
Y26500D01*
D02*
G03*
X5750Y31500I-5000J0D01*
G01*
X0D01*
X-0Y420000D01*
X220000D01*
X220000Y31500D01*
X214250D01*
D02*
G03*
X209250Y26500I0J-5000D01*
G01*
Y0D01*
X172250D01*
Y29000D01*
D02*
G03*
X160250Y29000I-6000J0D01*
G01*
Y0D01*
X10750D01*
M02*
